(kicad_pcb
	(version 20260206)
	(generator "pcbnew")
	(generator_version "10.0")
	(general
		(thickness 1.6)
		(legacy_teardrops no)
	)
	(paper "A4")
	(title_block
		(title "01162023_DA0F0TEBIF0_F0T_Expander_BD_F_brd_V02_OCP.brd")
		(comment 1 "Grand Teton / footprints 6878-6883 of 9728")
	)
	(layers
		(0 "F.Cu" signal "TOP")
		(4 "In1.Cu" signal "GND")
		(6 "In2.Cu" signal "VCC")
		(8 "In3.Cu" signal "VCC1")
		(10 "In4.Cu" signal "GND1")
		(12 "In5.Cu" signal "IN1")
		(14 "In6.Cu" signal "GND2")
		(16 "In7.Cu" signal "IN2")
		(18 "In8.Cu" signal "GND3")
		(20 "In9.Cu" signal "IN3")
		(22 "In10.Cu" signal "GND4")
		(24 "In11.Cu" signal "IN4")
		(26 "In12.Cu" signal "GND5")
		(28 "In13.Cu" signal "IN5")
		(30 "In14.Cu" signal "GND6")
		(32 "In15.Cu" signal "IN6")
		(34 "In16.Cu" signal "GND7")
		(2 "B.Cu" signal "BOTTOM")
		(9 "F.Adhes" user "F.Adhesive")
		(11 "B.Adhes" user "B.Adhesive")
		(13 "F.Paste" user "Package Geometry/Pastemask Top")
		(15 "B.Paste" user "Package Geometry/Pastemask Bottom")
		(5 "F.SilkS" user "Ref Des/Silkscreen Top")
		(7 "B.SilkS" user "Ref Des/Silkscreen Bottom")
		(1 "F.Mask" user "Board Geometry/Soldermask Top")
		(3 "B.Mask" user "Board Geometry/Soldermask Bottom")
		(17 "Dwgs.User" user "User.Drawings")
		(19 "Cmts.User" user "User.Comments")
		(21 "Eco1.User" user "User.Eco1")
		(23 "Eco2.User" user "User.Eco2")
		(25 "Edge.Cuts" user "Board Geometry/Outline")
		(27 "Margin" user)
		(31 "F.CrtYd" user "Package Geometry/Place Bound Top")
		(29 "B.CrtYd" user "Package Geometry/Place Bound Bottom")
		(35 "F.Fab" user "Ref Des/Assembly Top")
		(33 "B.Fab" user "Ref Des/Assembly Bottom")
	)
	(footprint ""
		(layer "F.Cu")
		(at 184.491884 -195.106798 180)
		(property "Reference" "R470"
			(at 0 0 180)
			(layer "F.SilkS")
			(hide yes)
			(effects
				(font
					(size 1.27 1.27)
				)
			)
		)
		(property "Value" ""
			(at 0 0 180)
			(layer "F.Fab")
			(effects
				(font
					(size 1.27 1.27)
				)
			)
		)
		(duplicate_pad_numbers_are_jumpers no)
		(fp_line
			(start 0.7874 0.4064)
			(end -0.7874 0.4064)
			(stroke
				(width 0.1524)
				(type default)
			)
			(layer "F.SilkS")
		)
		(fp_line
			(start 0.7874 -0.4064)
			(end 0.7874 0.4064)
			(stroke
				(width 0.1524)
				(type default)
			)
			(layer "F.SilkS")
		)
		(fp_line
			(start -0.7874 0.4064)
			(end -0.7874 -0.4064)
			(stroke
				(width 0.1524)
				(type default)
			)
			(layer "F.SilkS")
		)
		(fp_line
			(start -0.7874 -0.4064)
			(end 0.7874 -0.4064)
			(stroke
				(width 0.1524)
				(type default)
			)
			(layer "F.SilkS")
		)
		(fp_line
			(start 0.67945 0.3048)
			(end 0.120396 0.3048)
			(stroke
				(width 0.1)
				(type default)
			)
			(layer "F.Fab")
		)
		(fp_line
			(start 0.67945 -0.3048)
			(end 0.67945 0.3048)
			(stroke
				(width 0.1)
				(type default)
			)
			(layer "F.Fab")
		)
		(fp_line
			(start 0.12065 -0.2794)
			(end 0.12065 -0.3048)
			(stroke
				(width 0.1)
				(type default)
			)
			(layer "F.Fab")
		)
		(fp_line
			(start 0.12065 -0.3048)
			(end 0.67945 -0.3048)
			(stroke
				(width 0.1)
				(type default)
			)
			(layer "F.Fab")
		)
		(fp_line
			(start 0.120396 0.3048)
			(end 0.120396 0.2794)
			(stroke
				(width 0.1)
				(type default)
			)
			(layer "F.Fab")
		)
		(fp_line
			(start 0.120396 0.2794)
			(end -0.12065 0.2794)
			(stroke
				(width 0.1)
				(type default)
			)
			(layer "F.Fab")
		)
		(fp_line
			(start -0.12065 0.3048)
			(end -0.67945 0.3048)
			(stroke
				(width 0.1)
				(type default)
			)
			(layer "F.Fab")
		)
		(fp_line
			(start -0.12065 0.2794)
			(end -0.12065 0.3048)
			(stroke
				(width 0.1)
				(type default)
			)
			(layer "F.Fab")
		)
		(fp_line
			(start -0.12065 -0.2794)
			(end 0.12065 -0.2794)
			(stroke
				(width 0.1)
				(type default)
			)
			(layer "F.Fab")
		)
		(fp_line
			(start -0.12065 -0.305054)
			(end -0.12065 -0.2794)
			(stroke
				(width 0.1)
				(type default)
			)
			(layer "F.Fab")
		)
		(fp_line
			(start -0.67945 0.3048)
			(end -0.67945 -0.305054)
			(stroke
				(width 0.1)
				(type default)
			)
			(layer "F.Fab")
		)
		(fp_line
			(start -0.67945 -0.305054)
			(end -0.12065 -0.305054)
			(stroke
				(width 0.1)
				(type default)
			)
			(layer "F.Fab")
		)
		(pad "1" smd circle
			(at -0.40005 0 180)
			(size 0 0)
			(layers "F.Cu" "F.Mask" "F.Paste")
			(net "SPI_BIC1_CLK_R2")
		)
		(pad "2" smd circle
			(at 0.40005 0 180)
			(size 0 0)
			(layers "F.Cu" "F.Mask" "F.Paste")
			(net "SPI_BIC1_CLK_R3")
		)
	)
	(footprint ""
		(layer "F.Cu")
		(at 350.380554 -81.501234)
		(property "Reference" "R1601"
			(at 0 0 0)
			(layer "F.SilkS")
			(hide yes)
			(effects
				(font
					(size 1.27 1.27)
				)
			)
		)
		(property "Value" ""
			(at 0 0 0)
			(layer "F.Fab")
			(effects
				(font
					(size 1.27 1.27)
				)
			)
		)
		(duplicate_pad_numbers_are_jumpers no)
		(fp_line
			(start -0.7874 -0.4064)
			(end 0.7874 -0.4064)
			(stroke
				(width 0.1524)
				(type default)
			)
			(layer "F.SilkS")
		)
		(fp_line
			(start -0.7874 0.4064)
			(end -0.7874 -0.4064)
			(stroke
				(width 0.1524)
				(type default)
			)
			(layer "F.SilkS")
		)
		(fp_line
			(start 0.7874 -0.4064)
			(end 0.7874 0.4064)
			(stroke
				(width 0.1524)
				(type default)
			)
			(layer "F.SilkS")
		)
		(fp_line
			(start 0.7874 0.4064)
			(end -0.7874 0.4064)
			(stroke
				(width 0.1524)
				(type default)
			)
			(layer "F.SilkS")
		)
		(fp_line
			(start -0.67945 -0.305054)
			(end -0.12065 -0.305054)
			(stroke
				(width 0.1)
				(type default)
			)
			(layer "F.Fab")
		)
		(fp_line
			(start -0.67945 0.3048)
			(end -0.67945 -0.305054)
			(stroke
				(width 0.1)
				(type default)
			)
			(layer "F.Fab")
		)
		(fp_line
			(start -0.12065 -0.305054)
			(end -0.12065 -0.2794)
			(stroke
				(width 0.1)
				(type default)
			)
			(layer "F.Fab")
		)
		(fp_line
			(start -0.12065 -0.2794)
			(end 0.12065 -0.2794)
			(stroke
				(width 0.1)
				(type default)
			)
			(layer "F.Fab")
		)
		(fp_line
			(start -0.12065 0.2794)
			(end -0.12065 0.3048)
			(stroke
				(width 0.1)
				(type default)
			)
			(layer "F.Fab")
		)
		(fp_line
			(start -0.12065 0.3048)
			(end -0.67945 0.3048)
			(stroke
				(width 0.1)
				(type default)
			)
			(layer "F.Fab")
		)
		(fp_line
			(start 0.120396 0.2794)
			(end -0.12065 0.2794)
			(stroke
				(width 0.1)
				(type default)
			)
			(layer "F.Fab")
		)
		(fp_line
			(start 0.120396 0.3048)
			(end 0.120396 0.2794)
			(stroke
				(width 0.1)
				(type default)
			)
			(layer "F.Fab")
		)
		(fp_line
			(start 0.12065 -0.3048)
			(end 0.67945 -0.3048)
			(stroke
				(width 0.1)
				(type default)
			)
			(layer "F.Fab")
		)
		(fp_line
			(start 0.12065 -0.2794)
			(end 0.12065 -0.3048)
			(stroke
				(width 0.1)
				(type default)
			)
			(layer "F.Fab")
		)
		(fp_line
			(start 0.67945 -0.3048)
			(end 0.67945 0.3048)
			(stroke
				(width 0.1)
				(type default)
			)
			(layer "F.Fab")
		)
		(fp_line
			(start 0.67945 0.3048)
			(end 0.120396 0.3048)
			(stroke
				(width 0.1)
				(type default)
			)
			(layer "F.Fab")
		)
		(pad "1" smd circle
			(at -0.40005 0)
			(size 0 0)
			(layers "F.Cu" "F.Mask" "F.Paste")
			(net "P3V3_AUX")
		)
		(pad "2" smd circle
			(at 0.40005 0)
			(size 0 0)
			(layers "F.Cu" "F.Mask" "F.Paste")
			(net "SMB_BIC_I2C9_MUX1_SSD11_R_SCL")
		)
	)
	(footprint ""
		(layer "F.Cu")
		(at 16.785336 -273.216624)
		(property "Reference" "R769"
			(at 0 0 0)
			(layer "F.SilkS")
			(hide yes)
			(effects
				(font
					(size 1.27 1.27)
				)
			)
		)
		(property "Value" ""
			(at 0 0 0)
			(layer "F.Fab")
			(effects
				(font
					(size 1.27 1.27)
				)
			)
		)
		(duplicate_pad_numbers_are_jumpers no)
		(fp_line
			(start -0.7874 -0.4064)
			(end 0.7874 -0.4064)
			(stroke
				(width 0.1524)
				(type default)
			)
			(layer "F.SilkS")
		)
		(fp_line
			(start -0.7874 0.4064)
			(end -0.7874 -0.4064)
			(stroke
				(width 0.1524)
				(type default)
			)
			(layer "F.SilkS")
		)
		(fp_line
			(start 0.7874 -0.4064)
			(end 0.7874 0.4064)
			(stroke
				(width 0.1524)
				(type default)
			)
			(layer "F.SilkS")
		)
		(fp_line
			(start 0.7874 0.4064)
			(end -0.7874 0.4064)
			(stroke
				(width 0.1524)
				(type default)
			)
			(layer "F.SilkS")
		)
		(fp_line
			(start -0.67945 -0.305054)
			(end -0.12065 -0.305054)
			(stroke
				(width 0.1)
				(type default)
			)
			(layer "F.Fab")
		)
		(fp_line
			(start -0.67945 0.3048)
			(end -0.67945 -0.305054)
			(stroke
				(width 0.1)
				(type default)
			)
			(layer "F.Fab")
		)
		(fp_line
			(start -0.12065 -0.305054)
			(end -0.12065 -0.2794)
			(stroke
				(width 0.1)
				(type default)
			)
			(layer "F.Fab")
		)
		(fp_line
			(start -0.12065 -0.2794)
			(end 0.12065 -0.2794)
			(stroke
				(width 0.1)
				(type default)
			)
			(layer "F.Fab")
		)
		(fp_line
			(start -0.12065 0.2794)
			(end -0.12065 0.3048)
			(stroke
				(width 0.1)
				(type default)
			)
			(layer "F.Fab")
		)
		(fp_line
			(start -0.12065 0.3048)
			(end -0.67945 0.3048)
			(stroke
				(width 0.1)
				(type default)
			)
			(layer "F.Fab")
		)
		(fp_line
			(start 0.120396 0.2794)
			(end -0.12065 0.2794)
			(stroke
				(width 0.1)
				(type default)
			)
			(layer "F.Fab")
		)
		(fp_line
			(start 0.120396 0.3048)
			(end 0.120396 0.2794)
			(stroke
				(width 0.1)
				(type default)
			)
			(layer "F.Fab")
		)
		(fp_line
			(start 0.12065 -0.3048)
			(end 0.67945 -0.3048)
			(stroke
				(width 0.1)
				(type default)
			)
			(layer "F.Fab")
		)
		(fp_line
			(start 0.12065 -0.2794)
			(end 0.12065 -0.3048)
			(stroke
				(width 0.1)
				(type default)
			)
			(layer "F.Fab")
		)
		(fp_line
			(start 0.67945 -0.3048)
			(end 0.67945 0.3048)
			(stroke
				(width 0.1)
				(type default)
			)
			(layer "F.Fab")
		)
		(fp_line
			(start 0.67945 0.3048)
			(end 0.120396 0.3048)
			(stroke
				(width 0.1)
				(type default)
			)
			(layer "F.Fab")
		)
		(pad "1" smd circle
			(at -0.40005 0)
			(size 0 0)
			(layers "F.Cu" "F.Mask" "F.Paste")
			(net "PEX0_P1V25_ADC_A0")
		)
		(pad "2" smd circle
			(at 0.40005 0)
			(size 0 0)
			(layers "F.Cu" "F.Mask" "F.Paste")
			(net "P3V3_AUX")
		)
	)
	(footprint ""
		(layer "F.Cu")
		(at 275.963126 -402.33219 -90)
		(property "Reference" "R1805"
			(at 0 0 270)
			(layer "F.SilkS")
			(hide yes)
			(effects
				(font
					(size 1.27 1.27)
				)
			)
		)
		(property "Value" ""
			(at 0 0 270)
			(layer "F.Fab")
			(effects
				(font
					(size 1.27 1.27)
				)
			)
		)
		(duplicate_pad_numbers_are_jumpers no)
		(fp_line
			(start -0.7874 0.4064)
			(end -0.7874 -0.4064)
			(stroke
				(width 0.1524)
				(type default)
			)
			(layer "F.SilkS")
		)
		(fp_line
			(start 0.7874 0.4064)
			(end -0.7874 0.4064)
			(stroke
				(width 0.1524)
				(type default)
			)
			(layer "F.SilkS")
		)
		(fp_line
			(start -0.7874 -0.4064)
			(end 0.7874 -0.4064)
			(stroke
				(width 0.1524)
				(type default)
			)
			(layer "F.SilkS")
		)
		(fp_line
			(start 0.7874 -0.4064)
			(end 0.7874 0.4064)
			(stroke
				(width 0.1524)
				(type default)
			)
			(layer "F.SilkS")
		)
		(fp_line
			(start -0.67945 0.3048)
			(end -0.67945 -0.305054)
			(stroke
				(width 0.1)
				(type default)
			)
			(layer "F.Fab")
		)
		(fp_line
			(start -0.12065 0.3048)
			(end -0.67945 0.3048)
			(stroke
				(width 0.1)
				(type default)
			)
			(layer "F.Fab")
		)
		(fp_line
			(start 0.120396 0.3048)
			(end 0.120396 0.2794)
			(stroke
				(width 0.1)
				(type default)
			)
			(layer "F.Fab")
		)
		(fp_line
			(start 0.67945 0.3048)
			(end 0.120396 0.3048)
			(stroke
				(width 0.1)
				(type default)
			)
			(layer "F.Fab")
		)
		(fp_line
			(start -0.12065 0.2794)
			(end -0.12065 0.3048)
			(stroke
				(width 0.1)
				(type default)
			)
			(layer "F.Fab")
		)
		(fp_line
			(start 0.120396 0.2794)
			(end -0.12065 0.2794)
			(stroke
				(width 0.1)
				(type default)
			)
			(layer "F.Fab")
		)
		(fp_line
			(start -0.12065 -0.2794)
			(end 0.12065 -0.2794)
			(stroke
				(width 0.1)
				(type default)
			)
			(layer "F.Fab")
		)
		(fp_line
			(start 0.12065 -0.2794)
			(end 0.12065 -0.3048)
			(stroke
				(width 0.1)
				(type default)
			)
			(layer "F.Fab")
		)
		(fp_line
			(start 0.12065 -0.3048)
			(end 0.67945 -0.3048)
			(stroke
				(width 0.1)
				(type default)
			)
			(layer "F.Fab")
		)
		(fp_line
			(start 0.67945 -0.3048)
			(end 0.67945 0.3048)
			(stroke
				(width 0.1)
				(type default)
			)
			(layer "F.Fab")
		)
		(fp_line
			(start -0.67945 -0.305054)
			(end -0.12065 -0.305054)
			(stroke
				(width 0.1)
				(type default)
			)
			(layer "F.Fab")
		)
		(fp_line
			(start -0.12065 -0.305054)
			(end -0.12065 -0.2794)
			(stroke
				(width 0.1)
				(type default)
			)
			(layer "F.Fab")
		)
		(pad "1" smd circle
			(at -0.40005 0 270)
			(size 0 0)
			(layers "F.Cu" "F.Mask" "F.Paste")
			(net "P3V3_AUX")
		)
		(pad "2" smd circle
			(at 0.40005 0 270)
			(size 0 0)
			(layers "F.Cu" "F.Mask" "F.Paste")
			(net "MB_BMC_MON_ISO_R")
		)
	)
	(footprint ""
		(layer "F.Cu")
		(at 374.884188 -29.222954 -90)
		(property "Reference" "PC949"
			(at 0 0 270)
			(layer "F.SilkS")
			(hide yes)
			(effects
				(font
					(size 1.27 1.27)
				)
			)
		)
		(property "Value" ""
			(at 0 0 270)
			(layer "F.Fab")
			(effects
				(font
					(size 1.27 1.27)
				)
			)
		)
		(duplicate_pad_numbers_are_jumpers no)
		(fp_line
			(start -0.7874 0.4064)
			(end -0.7874 -0.4064)
			(stroke
				(width 0.1524)
				(type default)
			)
			(layer "F.SilkS")
		)
		(fp_line
			(start 0.7874 0.4064)
			(end -0.7874 0.4064)
			(stroke
				(width 0.1524)
				(type default)
			)
			(layer "F.SilkS")
		)
		(fp_line
			(start -0.7874 -0.4064)
			(end 0.7874 -0.4064)
			(stroke
				(width 0.1524)
				(type default)
			)
			(layer "F.SilkS")
		)
		(fp_line
			(start 0.7874 -0.4064)
			(end 0.7874 0.4064)
			(stroke
				(width 0.1524)
				(type default)
			)
			(layer "F.SilkS")
		)
		(fp_line
			(start -0.67945 0.3048)
			(end -0.67945 -0.305054)
			(stroke
				(width 0.1)
				(type default)
			)
			(layer "F.Fab")
		)
		(fp_line
			(start -0.12065 0.3048)
			(end -0.67945 0.3048)
			(stroke
				(width 0.1)
				(type default)
			)
			(layer "F.Fab")
		)
		(fp_line
			(start 0.120396 0.3048)
			(end 0.120396 0.2794)
			(stroke
				(width 0.1)
				(type default)
			)
			(layer "F.Fab")
		)
		(fp_line
			(start 0.67945 0.3048)
			(end 0.120396 0.3048)
			(stroke
				(width 0.1)
				(type default)
			)
			(layer "F.Fab")
		)
		(fp_line
			(start -0.12065 0.2794)
			(end -0.12065 0.3048)
			(stroke
				(width 0.1)
				(type default)
			)
			(layer "F.Fab")
		)
		(fp_line
			(start 0.120396 0.2794)
			(end -0.12065 0.2794)
			(stroke
				(width 0.1)
				(type default)
			)
			(layer "F.Fab")
		)
		(fp_line
			(start -0.12065 -0.2794)
			(end 0.12065 -0.2794)
			(stroke
				(width 0.1)
				(type default)
			)
			(layer "F.Fab")
		)
		(fp_line
			(start 0.12065 -0.2794)
			(end 0.12065 -0.3048)
			(stroke
				(width 0.1)
				(type default)
			)
			(layer "F.Fab")
		)
		(fp_line
			(start 0.12065 -0.3048)
			(end 0.67945 -0.3048)
			(stroke
				(width 0.1)
				(type default)
			)
			(layer "F.Fab")
		)
		(fp_line
			(start 0.67945 -0.3048)
			(end 0.67945 0.3048)
			(stroke
				(width 0.1)
				(type default)
			)
			(layer "F.Fab")
		)
		(fp_line
			(start -0.67945 -0.305054)
			(end -0.12065 -0.305054)
			(stroke
				(width 0.1)
				(type default)
			)
			(layer "F.Fab")
		)
		(fp_line
			(start -0.12065 -0.305054)
			(end -0.12065 -0.2794)
			(stroke
				(width 0.1)
				(type default)
			)
			(layer "F.Fab")
		)
		(pad "1" smd circle
			(at -0.40005 0 270)
			(size 0 0)
			(layers "F.Cu" "F.Mask" "F.Paste")
			(net "P3V3_AUX")
		)
		(pad "2" smd circle
			(at 0.40005 0 270)
			(size 0 0)
			(layers "F.Cu" "F.Mask" "F.Paste")
			(net "GND")
		)
	)
	(footprint ""
		(layer "F.Cu")
		(at 353.822 -178.562)
		(property "Reference" "R4758"
			(at 0 0 0)
			(layer "F.SilkS")
			(hide yes)
			(effects
				(font
					(size 1.27 1.27)
				)
			)
		)
		(property "Value" ""
			(at 0 0 0)
			(layer "F.Fab")
			(effects
				(font
					(size 1.27 1.27)
				)
			)
		)
		(duplicate_pad_numbers_are_jumpers no)
		(fp_line
			(start -0.7874 -0.4064)
			(end 0.7874 -0.4064)
			(stroke
				(width 0.1524)
				(type default)
			)
			(layer "F.SilkS")
		)
		(fp_line
			(start -0.7874 0.4064)
			(end -0.7874 -0.4064)
			(stroke
				(width 0.1524)
				(type default)
			)
			(layer "F.SilkS")
		)
		(fp_line
			(start 0.7874 -0.4064)
			(end 0.7874 0.4064)
			(stroke
				(width 0.1524)
				(type default)
			)
			(layer "F.SilkS")
		)
		(fp_line
			(start 0.7874 0.4064)
			(end -0.7874 0.4064)
			(stroke
				(width 0.1524)
				(type default)
			)
			(layer "F.SilkS")
		)
		(fp_line
			(start -0.67945 -0.305054)
			(end -0.12065 -0.305054)
			(stroke
				(width 0.1)
				(type default)
			)
			(layer "F.Fab")
		)
		(fp_line
			(start -0.67945 0.3048)
			(end -0.67945 -0.305054)
			(stroke
				(width 0.1)
				(type default)
			)
			(layer "F.Fab")
		)
		(fp_line
			(start -0.12065 -0.305054)
			(end -0.12065 -0.2794)
			(stroke
				(width 0.1)
				(type default)
			)
			(layer "F.Fab")
		)
		(fp_line
			(start -0.12065 -0.2794)
			(end 0.12065 -0.2794)
			(stroke
				(width 0.1)
				(type default)
			)
			(layer "F.Fab")
		)
		(fp_line
			(start -0.12065 0.2794)
			(end -0.12065 0.3048)
			(stroke
				(width 0.1)
				(type default)
			)
			(layer "F.Fab")
		)
		(fp_line
			(start -0.12065 0.3048)
			(end -0.67945 0.3048)
			(stroke
				(width 0.1)
				(type default)
			)
			(layer "F.Fab")
		)
		(fp_line
			(start 0.120396 0.2794)
			(end -0.12065 0.2794)
			(stroke
				(width 0.1)
				(type default)
			)
			(layer "F.Fab")
		)
		(fp_line
			(start 0.120396 0.3048)
			(end 0.120396 0.2794)
			(stroke
				(width 0.1)
				(type default)
			)
			(layer "F.Fab")
		)
		(fp_line
			(start 0.12065 -0.3048)
			(end 0.67945 -0.3048)
			(stroke
				(width 0.1)
				(type default)
			)
			(layer "F.Fab")
		)
		(fp_line
			(start 0.12065 -0.2794)
			(end 0.12065 -0.3048)
			(stroke
				(width 0.1)
				(type default)
			)
			(layer "F.Fab")
		)
		(fp_line
			(start 0.67945 -0.3048)
			(end 0.67945 0.3048)
			(stroke
				(width 0.1)
				(type default)
			)
			(layer "F.Fab")
		)
		(fp_line
			(start 0.67945 0.3048)
			(end 0.120396 0.3048)
			(stroke
				(width 0.1)
				(type default)
			)
			(layer "F.Fab")
		)
		(pad "1" smd circle
			(at -0.40005 0)
			(size 0 0)
			(layers "F.Cu" "F.Mask" "F.Paste")
			(net "NIC4_PEX_PWR_EN")
		)
		(pad "2" smd circle
			(at 0.40005 0)
			(size 0 0)
			(layers "F.Cu" "F.Mask" "F.Paste")
			(net "NIC4_PEX_PWR_EN_R")
		)
	)
)
